# Bryce Canyon_IOM_M2_Stackup.xlsx — PCB Test Plan_HVM(90+) (pcb-stackup)
|  | Board vendor give feedback of quantity in yellow columns based on the AQL table or description. |  |  |  |  |  |  |  |  |  |  |  |  |  |  |
|  | Wiwynn PM give feedback in blue columns |  |  |  |  |  |  |  |  |  |  |  |  |  |  |
| Person to be informed : PCB vendor, EE, SI, PM, PSM, Buyer, SQM |  |  |  |  |  |  |  |  |  |  |  |  |  |  |  |
| Simple flow : SI (test requirements) -> PM/AM (Total PCBS demand) -> Buyer -> Board Vendor (yellow column feedback) -> Buyer -> Person to be informed (Check and Track) |  |  |  |  |  |  |  |  |  |  |  |  |  |  |  |
| PO(purchase order) : If there are many POs for this PCB, 1st sample quantity is based on 1st PO, 2nd sample quantity is based on 2nd PO. |  |  |  |  |  |  |  |  |  |  |  |  |  |  |  |
| Project Name | PCB name | PCB# (1XXXX-XX) | Product Stage | Batch# | PCB Vendor | Production  Lot size | PCBs Demand | Delta-L Coupon (PCB Vendor) | Delta-L Coupon (3rd Party Lab) | Impedance Coupon (PCB Vendor) | In-board trace correlation (PCB Vendor) | X-section Analysis (PCB Vendor) | IST (3rd Party Lab) | IPC-6012D (3rd Party Lab) | Note |
| Bryce Canyon | FDPB | 16315-1 | HVM(90+ days) | N/A |  |  | TBD | Yes | No | Yes | No | No | No | No | Need Test? (Yes, No) |
| Tracking Code On Both Of Coupon And PCB |  |  |  |  |  |  |  | N/A |  | N/A |  |  |  |  |  |
| Test Item Acceptance Criteria |  |  |  |  |  |  |  | c = 0 |  | c = 0 |  |  |  |  |  |
| Test Item Sampling Quantity |  |  |  |  |  |  |  | 5 pcs/production lot/quarter, with max total of 30 pcs |  | Mil-STD 105E single sampling plan, AQL 0.65, level 2 |  |  |  |  |  |
| Test Time(working days) |  |  |  |  |  |  |  |  |  |  |  |  |  |  |  |
| Test Item Shipping Quantity |  |  |  |  |  |  |  |  |  |  |  |  |  |  |  |
| Shipping Address |  |  |  |  |  |  |  |  |  |  |  |  |  |  |  |
| Receiver Name |  |  |  |  |  |  |  |  |  |  |  |  |  |  |  |
| Receiver Phone# |  |  |  |  |  |  |  |  |  |  |  |  |  |  |  |
| Project Name | PCB name | PCB# (1XXXX-XX) | Product Stage | Batch# | PCB Vendor | Production  Lot size | PCBs Demand | Delta-L Coupon (PCB Vendor) | Delta-L Coupon (3rd Party Lab) | Impedance Coupon (PCB Vendor) | In-board trace correlation (PCB Vendor) | X-section Analysis (PCB Vendor) | IST (3rd Party Lab) | IPC-6012D (3rd Party Lab) | Note |
| Bryce Canyon | SCC | 16316-1 | HVM(90+ days) | N/A |  |  | TBD | No | No | Yes | No | No | No | No | Need Test? (Yes, No) |
| Tracking Code On Both Of Coupon And PCB |  |  |  |  |  |  |  |  |  | N/A |  |  |  |  |  |
| Test Item Acceptance Criteria |  |  |  |  |  |  |  |  |  | c = 0 |  |  |  |  |  |
| Test Item Sampling Quantity |  |  |  |  |  |  |  |  |  | Mil-STD 105E single sampling plan, AQL 0.65, level 2 |  |  |  |  |  |
| Test Time (working days) |  |  |  |  |  |  |  |  |  |  |  |  |  |  |  |
| Test Item Shipping Quantity |  |  |  |  |  |  |  |  |  |  |  |  |  |  |  |
| Shipping Address |  |  |  |  |  |  |  |  |  |  |  |  |  |  |  |
| Receiver Name |  |  |  |  |  |  |  |  |  |  |  |  |  |  |  |
| Receiver Phone# |  |  |  |  |  |  |  |  |  |  |  |  |  |  |  |
| Project Name | PCB name | PCB# (1XXXX-XX) | Product Stage | Batch# | PCB Vendor | Production  Lot size | PCBs Demand | Delta-L Coupon (PCB Vendor) | Delta-L Coupon (3rd Party Lab) | Impedance Coupon (PCB Vendor) | In-board trace correlation (PCB Vendor) | X-section Analysis (PCB Vendor) | IST (3rd Party Lab) | IPC-6012D (3rd Party Lab) | Note |
| Bryce Canyon | RDPB | 16317-1 | HVM(90+ days) | N/A |  |  | TBD | Yes | No | Yes | No | No | No | No | Need Test? (Yes, No) |
| Tracking Code On Both Of Coupon And PCB |  |  |  |  |  |  |  | N/A |  | N/A |  |  |  |  |  |
| Test Item Acceptance Criteria |  |  |  |  |  |  |  | c = 0 |  | c = 0 |  |  |  |  |  |
| Test Item Sampling Quantity |  |  |  |  |  |  |  | 5 pcs/production lot/quarter, with max total of 30 pcs |  | Mil-STD 105E single sampling plan, AQL 0.65, level 2 |  |  |  |  |  |
| Test Time (working days) |  |  |  |  |  |  |  |  |  |  |  |  |  |  |  |
| Test Item Shipping Quantity |  |  |  |  |  |  |  |  |  |  |  |  |  |  |  |
| Shipping Address |  |  |  |  |  |  |  |  |  |  |  |  |  |  |  |
| Receiver Name |  |  |  |  |  |  |  |  |  |  |  |  |  |  |  |
| Receiver Phone# |  |  |  |  |  |  |  |  |  |  |  |  |  |  |  |
| Project Name | PCB name | PCB# (1XXXX-XX) | Product Stage | Batch# | PCB Vendor | Production  Lot size | PCBs Demand | Delta-L Coupon (PCB Vendor) | Delta-L Coupon (3rd Party Lab) | Impedance Coupon (PCB Vendor) | In-board trace correlation (PCB Vendor) | X-section Analysis (PCB Vendor) | IST (3rd Party Lab) | IPC-6012D (3rd Party Lab) | Note |
| Bryce Canyon | IOM IOC | 16318-2 | HVM(90+ days) | N/A |  |  | TBD | No | No | Yes | No | No | No | No | Need Test? (Yes, No) |
| Tracking Code On Both Of Coupon And PCB |  |  |  |  |  |  |  |  |  | N/A |  |  |  |  |  |
| Test Item Acceptance Criteria |  |  |  |  |  |  |  |  |  | c = 0 |  |  |  |  |  |
| Test Item Sampling Quantity |  |  |  |  |  |  |  |  |  | Mil-STD 105E single sampling plan, AQL 0.65, level 2 |  |  |  |  |  |
| Test Time (working days) |  |  |  |  |  |  |  |  |  |  |  |  |  |  |  |
| Test Item Shipping Quantity |  |  |  |  |  |  |  |  |  |  |  |  |  |  |  |
| Shipping Address |  |  |  |  |  |  |  |  |  |  |  |  |  |  |  |
| Receiver Name |  |  |  |  |  |  |  |  |  |  |  |  |  |  |  |
| Receiver Phone# |  |  |  |  |  |  |  |  |  |  |  |  |  |  |  |
| Project Name | PCB name | PCB# (1XXXX-XX) | Product Stage | Batch# | PCB Vendor | Production  Lot size | PCBs Demand | Delta-L Coupon (PCB Vendor) | Delta-L Coupon (3rd Party Lab) | Impedance Coupon (PCB Vendor) | In-board trace correlation (PCB Vendor) | X-section Analysis (PCB Vendor) | IST (3rd Party Lab) | IPC-6012D (3rd Party Lab) | Note |
| Bryce Canyon | IOM M2 | 16342-2 | HVM(90+ days) | N/A |  |  | TBD | No | No | Yes | No | No | No | No | Need Test? (Yes, No) |
| Tracking Code On Both Of Coupon And PCB |  |  |  |  |  |  |  |  |  | N/A |  |  |  |  |  |
| Test Item Acceptance Criteria |  |  |  |  |  |  |  |  |  | c = 0 |  |  |  |  |  |
| Test Item Sampling Quantity |  |  |  |  |  |  |  |  |  | Mil-STD 105E single sampling plan, AQL 0.65, level 2 |  |  |  |  |  |
| Test Time (working days) |  |  |  |  |  |  |  |  |  |  |  |  |  |  |  |
| Test Item Shipping Quantity |  |  |  |  |  |  |  |  |  |  |  |  |  |  |  |
| Shipping Address |  |  |  |  |  |  |  |  |  |  |  |  |  |  |  |
| Receiver Name |  |  |  |  |  |  |  |  |  |  |  |  |  |  |  |
| Receiver Phone# |  |  |  |  |  |  |  |  |  |  |  |  |  |  |  |
